# T6G (Grand Teton) — schematic netlist excerpt (pin names and nets, part order shuffled) for the footprints in the layout excerpt that follows; sources: Cadence DE-HDL packaged netlist, KiCad conversion of 04192023_DAF0TMB3IC0_F0TG_MB_C_brd_V02_OCP.brd

PC2162  Q_CAP  100PF 50V 5% X7R  pkg 0402  page 135 : A = P3V3_OCP_GATE_1 ; B = GND
L12  Q_INDUCTOR  100NH/16A IND  pkg SMLF  page 279 : \1\ = P0V9_CPU0_RT_2D ; \2\ = P0V9_CPU0_RT0_2A
R1497  Q_RES  33 5% CHIP  pkg 0402LF  page 151 : A = SMB_VR_3V3AUX_SCL ; B = SMB_SCM_2_R3_SCL

(kicad_pcb
	(version 20260206)
	(generator "pcbnew")
	(generator_version "10.0")
	(general
		(thickness 1.6)
		(legacy_teardrops no)
	)
	(paper "A4")
	(title_block
		(title "04192023_DAF0TMB3IC0_F0TG_MB_C_brd_V02_OCP.brd")
		(comment 1 "Grand Teton / footprints 3203-3205 of 8354")
	)
	(layers
		(0 "F.Cu" signal "TOP")
		(4 "In1.Cu" signal "GND")
		(6 "In2.Cu" signal "IN1")
		(8 "In3.Cu" signal "GND1")
		(10 "In4.Cu" signal "IN2")
		(12 "In5.Cu" signal "GND2")
		(14 "In6.Cu" signal "IN3")
		(16 "In7.Cu" signal "GND3")
		(18 "In8.Cu" signal "VCC")
		(20 "In9.Cu" signal "VCC1")
		(22 "In10.Cu" signal "GND4")
		(24 "In11.Cu" signal "IN4")
		(26 "In12.Cu" signal "GND5")
		(28 "In13.Cu" signal "IN5")
		(30 "In14.Cu" signal "GND6")
		(32 "In15.Cu" signal "IN6")
		(34 "In16.Cu" signal "GND7")
		(2 "B.Cu" signal "BOTTOM")
		(9 "F.Adhes" user "F.Adhesive")
		(11 "B.Adhes" user "B.Adhesive")
		(13 "F.Paste" user "Package Geometry/Pastemask Top")
		(15 "B.Paste" user "Package Geometry/Pastemask Bottom")
		(5 "F.SilkS" user "Ref Des/Silkscreen Top")
		(7 "B.SilkS" user "Ref Des/Silkscreen Bottom")
		(1 "F.Mask" user "Board Geometry/Soldermask Top")
		(3 "B.Mask" user "Board Geometry/Soldermask Bottom")
		(17 "Dwgs.User" user "User.Drawings")
		(19 "Cmts.User" user "User.Comments")
		(21 "Eco1.User" user "User.Eco1")
		(23 "Eco2.User" user "User.Eco2")
		(25 "Edge.Cuts" user "Board Geometry/Outline")
		(27 "Margin" user)
		(31 "F.CrtYd" user "Package Geometry/Place Bound Top")
		(29 "B.CrtYd" user "Package Geometry/Place Bound Bottom")
		(35 "F.Fab" user "Ref Des/Assembly Top")
		(33 "B.Fab" user "Ref Des/Assembly Bottom")
	)
	(footprint ""
		(layer "F.Cu")
		(at 421.92194 -109.271308 90)
		(property "Reference" "PC2162"
			(at 0 0 90)
			(layer "F.SilkS")
			(hide yes)
			(effects
				(font
					(size 1.27 1.27)
				)
			)
		)
		(property "Value" ""
			(at 0 0 90)
			(layer "F.Fab")
			(effects
				(font
					(size 1.27 1.27)
				)
			)
		)
		(duplicate_pad_numbers_are_jumpers no)
		(fp_line
			(start 0.7874 -0.4064)
			(end 0.7874 0.4064)
			(stroke
				(width 0.1524)
				(type default)
			)
			(layer "F.SilkS")
		)
		(fp_line
			(start -0.7874 -0.4064)
			(end 0.7874 -0.4064)
			(stroke
				(width 0.1524)
				(type default)
			)
			(layer "F.SilkS")
		)
		(fp_line
			(start 0.7874 0.4064)
			(end -0.7874 0.4064)
			(stroke
				(width 0.1524)
				(type default)
			)
			(layer "F.SilkS")
		)
		(fp_line
			(start -0.7874 0.4064)
			(end -0.7874 -0.4064)
			(stroke
				(width 0.1524)
				(type default)
			)
			(layer "F.SilkS")
		)
		(fp_line
			(start -0.12065 -0.305054)
			(end -0.12065 -0.2794)
			(stroke
				(width 0.1)
				(type default)
			)
			(layer "F.Fab")
		)
		(fp_line
			(start -0.67945 -0.305054)
			(end -0.12065 -0.305054)
			(stroke
				(width 0.1)
				(type default)
			)
			(layer "F.Fab")
		)
		(fp_line
			(start 0.67945 -0.3048)
			(end 0.67945 0.3048)
			(stroke
				(width 0.1)
				(type default)
			)
			(layer "F.Fab")
		)
		(fp_line
			(start 0.12065 -0.3048)
			(end 0.67945 -0.3048)
			(stroke
				(width 0.1)
				(type default)
			)
			(layer "F.Fab")
		)
		(fp_line
			(start 0.12065 -0.2794)
			(end 0.12065 -0.3048)
			(stroke
				(width 0.1)
				(type default)
			)
			(layer "F.Fab")
		)
		(fp_line
			(start -0.12065 -0.2794)
			(end 0.12065 -0.2794)
			(stroke
				(width 0.1)
				(type default)
			)
			(layer "F.Fab")
		)
		(fp_line
			(start 0.120396 0.2794)
			(end -0.12065 0.2794)
			(stroke
				(width 0.1)
				(type default)
			)
			(layer "F.Fab")
		)
		(fp_line
			(start -0.12065 0.2794)
			(end -0.12065 0.3048)
			(stroke
				(width 0.1)
				(type default)
			)
			(layer "F.Fab")
		)
		(fp_line
			(start 0.67945 0.3048)
			(end 0.120396 0.3048)
			(stroke
				(width 0.1)
				(type default)
			)
			(layer "F.Fab")
		)
		(fp_line
			(start 0.120396 0.3048)
			(end 0.120396 0.2794)
			(stroke
				(width 0.1)
				(type default)
			)
			(layer "F.Fab")
		)
		(fp_line
			(start -0.12065 0.3048)
			(end -0.67945 0.3048)
			(stroke
				(width 0.1)
				(type default)
			)
			(layer "F.Fab")
		)
		(fp_line
			(start -0.67945 0.3048)
			(end -0.67945 -0.305054)
			(stroke
				(width 0.1)
				(type default)
			)
			(layer "F.Fab")
		)
		(pad "1" smd circle
			(at -0.40005 0 90)
			(size 0 0)
			(layers "F.Cu" "F.Mask" "F.Paste")
			(net "P3V3_OCP_GATE_1")
		)
		(pad "2" smd circle
			(at 0.40005 0 90)
			(size 0 0)
			(layers "F.Cu" "F.Mask" "F.Paste")
			(net "GND")
		)
	)
	(footprint ""
		(layer "F.Cu")
		(at 298.316142 -404.4188 -90)
		(property "Reference" "L12"
			(at -0.2286 -3.048508 90)
			(unlocked yes)
			(layer "F.SilkS")
			(effects
				(font
					(size 0.7874 0.5842)
					(thickness 0.1524)
				)
				(justify left)
			)
		)
		(property "Value" ""
			(at 0 0 270)
			(layer "F.Fab")
			(effects
				(font
					(size 1.27 1.27)
				)
			)
		)
		(duplicate_pad_numbers_are_jumpers no)
		(fp_line
			(start -2.249932 2.249932)
			(end -2.249932 1.3843)
			(stroke
				(width 0.1524)
				(type default)
			)
			(layer "F.SilkS")
		)
		(fp_line
			(start 2.249932 2.249932)
			(end -2.249932 2.249932)
			(stroke
				(width 0.1524)
				(type default)
			)
			(layer "F.SilkS")
		)
		(fp_line
			(start 2.249932 1.3843)
			(end 2.249932 2.249932)
			(stroke
				(width 0.1524)
				(type default)
			)
			(layer "F.SilkS")
		)
		(fp_line
			(start -2.249932 -1.3843)
			(end -2.249932 -2.249932)
			(stroke
				(width 0.1524)
				(type default)
			)
			(layer "F.SilkS")
		)
		(fp_line
			(start -2.249932 -2.249932)
			(end 2.249932 -2.249932)
			(stroke
				(width 0.1524)
				(type default)
			)
			(layer "F.SilkS")
		)
		(fp_line
			(start 2.249932 -2.249932)
			(end 2.249932 -1.3843)
			(stroke
				(width 0.1524)
				(type default)
			)
			(layer "F.SilkS")
		)
		(fp_line
			(start -2.249932 2.249932)
			(end -2.249932 -2.249932)
			(stroke
				(width 0.1)
				(type default)
			)
			(layer "F.Fab")
		)
		(fp_line
			(start 2.249932 2.249932)
			(end -2.249932 2.249932)
			(stroke
				(width 0.1)
				(type default)
			)
			(layer "F.Fab")
		)
		(fp_line
			(start -2.249932 -2.249932)
			(end 2.249932 -2.249932)
			(stroke
				(width 0.1)
				(type default)
			)
			(layer "F.Fab")
		)
		(fp_line
			(start 2.249932 -2.249932)
			(end 2.249932 2.249932)
			(stroke
				(width 0.1)
				(type default)
			)
			(layer "F.Fab")
		)
		(pad "1" smd rect
			(at -1.82499 0 270)
			(size 1.0668 2.5146)
			(layers "F.Cu" "F.Mask" "F.Paste")
			(net "P0V9_CPU0_RT_2D")
		)
		(pad "2" smd rect
			(at 1.82499 0 270)
			(size 1.0668 2.5146)
			(layers "F.Cu" "F.Mask" "F.Paste")
			(net "P0V9_CPU0_RT0_2A")
		)
	)
	(footprint ""
		(layer "F.Cu")
		(at 252.573536 -120.31345 180)
		(property "Reference" "R1497"
			(at 0 0 180)
			(layer "F.SilkS")
			(hide yes)
			(effects
				(font
					(size 1.27 1.27)
				)
			)
		)
		(property "Value" ""
			(at 0 0 180)
			(layer "F.Fab")
			(effects
				(font
					(size 1.27 1.27)
				)
			)
		)
		(duplicate_pad_numbers_are_jumpers no)
		(fp_line
			(start 0.7874 0.4064)
			(end -0.7874 0.4064)
			(stroke
				(width 0.1524)
				(type default)
			)
			(layer "F.SilkS")
		)
		(fp_line
			(start 0.7874 -0.4064)
			(end 0.7874 0.4064)
			(stroke
				(width 0.1524)
				(type default)
			)
			(layer "F.SilkS")
		)
		(fp_line
			(start -0.7874 0.4064)
			(end -0.7874 -0.4064)
			(stroke
				(width 0.1524)
				(type default)
			)
			(layer "F.SilkS")
		)
		(fp_line
			(start -0.7874 -0.4064)
			(end 0.7874 -0.4064)
			(stroke
				(width 0.1524)
				(type default)
			)
			(layer "F.SilkS")
		)
		(fp_line
			(start 0.67945 0.3048)
			(end 0.120396 0.3048)
			(stroke
				(width 0.1)
				(type default)
			)
			(layer "F.Fab")
		)
		(fp_line
			(start 0.67945 -0.3048)
			(end 0.67945 0.3048)
			(stroke
				(width 0.1)
				(type default)
			)
			(layer "F.Fab")
		)
		(fp_line
			(start 0.12065 -0.2794)
			(end 0.12065 -0.3048)
			(stroke
				(width 0.1)
				(type default)
			)
			(layer "F.Fab")
		)
		(fp_line
			(start 0.12065 -0.3048)
			(end 0.67945 -0.3048)
			(stroke
				(width 0.1)
				(type default)
			)
			(layer "F.Fab")
		)
		(fp_line
			(start 0.120396 0.3048)
			(end 0.120396 0.2794)
			(stroke
				(width 0.1)
				(type default)
			)
			(layer "F.Fab")
		)
		(fp_line
			(start 0.120396 0.2794)
			(end -0.12065 0.2794)
			(stroke
				(width 0.1)
				(type default)
			)
			(layer "F.Fab")
		)
		(fp_line
			(start -0.12065 0.3048)
			(end -0.67945 0.3048)
			(stroke
				(width 0.1)
				(type default)
			)
			(layer "F.Fab")
		)
		(fp_line
			(start -0.12065 0.2794)
			(end -0.12065 0.3048)
			(stroke
				(width 0.1)
				(type default)
			)
			(layer "F.Fab")
		)
		(fp_line
			(start -0.12065 -0.2794)
			(end 0.12065 -0.2794)
			(stroke
				(width 0.1)
				(type default)
			)
			(layer "F.Fab")
		)
		(fp_line
			(start -0.12065 -0.305054)
			(end -0.12065 -0.2794)
			(stroke
				(width 0.1)
				(type default)
			)
			(layer "F.Fab")
		)
		(fp_line
			(start -0.67945 0.3048)
			(end -0.67945 -0.305054)
			(stroke
				(width 0.1)
				(type default)
			)
			(layer "F.Fab")
		)
		(fp_line
			(start -0.67945 -0.305054)
			(end -0.12065 -0.305054)
			(stroke
				(width 0.1)
				(type default)
			)
			(layer "F.Fab")
		)
		(pad "1" smd circle
			(at -0.40005 0 180)
			(size 0 0)
			(layers "F.Cu" "F.Mask" "F.Paste")
			(net "SMB_VR_3V3AUX_SCL")
		)
		(pad "2" smd circle
			(at 0.40005 0 180)
			(size 0 0)
			(layers "F.Cu" "F.Mask" "F.Paste")
			(net "SMB_SCM_2_R3_SCL")
		)
	)
)
